# S9S_MB_2U (Grand Teton) — schematic netlist excerpt (pin names and nets, part order shuffled) for the footprints in the layout excerpt that follows; sources: Cadence DE-HDL packaged netlist, KiCad conversion of 03242023_DA0F0TMBIJ0_F0T_Motherboard_J_brd_V01_OCP.brd

C1242  Q_CAP  2.2UF 10V 10% X6S  pkg C0402  page 189 : A = P1V05_PCH_AUX ; B = GND
R889  Q_RES  33.2 1% CHIP  pkg 0402LF  page 114 : A = PWRGD_CHG_CPU0_DIMM1 ; B = PWRGD_FAIL_CPU0_GH

(kicad_pcb
	(version 20260206)
	(generator "pcbnew")
	(generator_version "10.0")
	(general
		(thickness 1.6)
		(legacy_teardrops no)
	)
	(paper "A4")
	(title_block
		(title "03242023_DA0F0TMBIJ0_F0T_Motherboard_J_brd_V01_OCP.brd")
		(comment 1 "Grand Teton / footprints 5184-5185 of 6105")
	)
	(layers
		(0 "F.Cu" signal "TOP")
		(4 "In1.Cu" signal "GND")
		(6 "In2.Cu" signal "IN1")
		(8 "In3.Cu" signal "GND1")
		(10 "In4.Cu" signal "IN2")
		(12 "In5.Cu" signal "GND2")
		(14 "In6.Cu" signal "IN3")
		(16 "In7.Cu" signal "GND3")
		(18 "In8.Cu" signal "VCC")
		(20 "In9.Cu" signal "VCC1")
		(22 "In10.Cu" signal "GND4")
		(24 "In11.Cu" signal "IN4")
		(26 "In12.Cu" signal "GND5")
		(28 "In13.Cu" signal "IN5")
		(30 "In14.Cu" signal "GND6")
		(32 "In15.Cu" signal "IN6")
		(34 "In16.Cu" signal "GND7")
		(2 "B.Cu" signal "BOTTOM")
		(9 "F.Adhes" user "F.Adhesive")
		(11 "B.Adhes" user "B.Adhesive")
		(13 "F.Paste" user "Package Geometry/Pastemask Top")
		(15 "B.Paste" user "Package Geometry/Pastemask Bottom")
		(5 "F.SilkS" user "Ref Des/Silkscreen Top")
		(7 "B.SilkS" user "Ref Des/Silkscreen Bottom")
		(1 "F.Mask" user "Board Geometry/Soldermask Top")
		(3 "B.Mask" user "Board Geometry/Soldermask Bottom")
		(17 "Dwgs.User" user "User.Drawings")
		(19 "Cmts.User" user "User.Comments")
		(21 "Eco1.User" user "User.Eco1")
		(23 "Eco2.User" user "User.Eco2")
		(25 "Edge.Cuts" user "Board Geometry/Outline")
		(27 "Margin" user)
		(31 "F.CrtYd" user "Package Geometry/Place Bound Top")
		(29 "B.CrtYd" user "Package Geometry/Place Bound Bottom")
		(35 "F.Fab" user "Ref Des/Assembly Top")
		(33 "B.Fab" user "Ref Des/Assembly Bottom")
	)
	(footprint ""
		(layer "B.Cu")
		(at 448.186556 -318.908176 90)
		(property "Reference" "R889"
			(at 0 0 90)
			(layer "B.SilkS")
			(hide yes)
			(effects
				(font
					(size 1.27 1.27)
				)
				(justify mirror)
			)
		)
		(property "Value" ""
			(at 0 0 90)
			(layer "B.Fab")
			(effects
				(font
					(size 1.27 1.27)
				)
				(justify mirror)
			)
		)
		(duplicate_pad_numbers_are_jumpers no)
		(fp_line
			(start 0.7874 -0.4064)
			(end -0.7874 -0.4064)
			(stroke
				(width 0.1524)
				(type default)
			)
			(layer "B.SilkS")
		)
		(fp_line
			(start -0.7874 -0.4064)
			(end -0.7874 0.4064)
			(stroke
				(width 0.1524)
				(type default)
			)
			(layer "B.SilkS")
		)
		(fp_line
			(start 0.7874 0.4064)
			(end 0.7874 -0.4064)
			(stroke
				(width 0.1524)
				(type default)
			)
			(layer "B.SilkS")
		)
		(fp_line
			(start -0.7874 0.4064)
			(end 0.7874 0.4064)
			(stroke
				(width 0.1524)
				(type default)
			)
			(layer "B.SilkS")
		)
		(fp_line
			(start 0.67945 -0.305054)
			(end 0.12065 -0.305054)
			(stroke
				(width 0.1)
				(type default)
			)
			(layer "B.Fab")
		)
		(fp_line
			(start 0.12065 -0.305054)
			(end 0.12065 -0.2794)
			(stroke
				(width 0.1)
				(type default)
			)
			(layer "B.Fab")
		)
		(fp_line
			(start -0.12065 -0.3048)
			(end -0.67945 -0.3048)
			(stroke
				(width 0.1)
				(type default)
			)
			(layer "B.Fab")
		)
		(fp_line
			(start -0.67945 -0.3048)
			(end -0.67945 0.3048)
			(stroke
				(width 0.1)
				(type default)
			)
			(layer "B.Fab")
		)
		(fp_line
			(start 0.12065 -0.2794)
			(end -0.12065 -0.2794)
			(stroke
				(width 0.1)
				(type default)
			)
			(layer "B.Fab")
		)
		(fp_line
			(start -0.12065 -0.2794)
			(end -0.12065 -0.3048)
			(stroke
				(width 0.1)
				(type default)
			)
			(layer "B.Fab")
		)
		(fp_line
			(start 0.12065 0.2794)
			(end 0.12065 0.3048)
			(stroke
				(width 0.1)
				(type default)
			)
			(layer "B.Fab")
		)
		(fp_line
			(start -0.120396 0.2794)
			(end 0.12065 0.2794)
			(stroke
				(width 0.1)
				(type default)
			)
			(layer "B.Fab")
		)
		(fp_line
			(start 0.67945 0.3048)
			(end 0.67945 -0.305054)
			(stroke
				(width 0.1)
				(type default)
			)
			(layer "B.Fab")
		)
		(fp_line
			(start 0.12065 0.3048)
			(end 0.67945 0.3048)
			(stroke
				(width 0.1)
				(type default)
			)
			(layer "B.Fab")
		)
		(fp_line
			(start -0.120396 0.3048)
			(end -0.120396 0.2794)
			(stroke
				(width 0.1)
				(type default)
			)
			(layer "B.Fab")
		)
		(fp_line
			(start -0.67945 0.3048)
			(end -0.120396 0.3048)
			(stroke
				(width 0.1)
				(type default)
			)
			(layer "B.Fab")
		)
		(pad "1" smd circle
			(at 0.40005 0 270)
			(size 0 0)
			(layers "B.Cu" "B.Mask" "B.Paste")
			(net "PWRGD_CHG_CPU0_DIMM1")
		)
		(pad "2" smd circle
			(at -0.40005 0 270)
			(size 0 0)
			(layers "B.Cu" "B.Mask" "B.Paste")
			(net "PWRGD_FAIL_CPU0_GH")
		)
	)
	(footprint ""
		(layer "B.Cu")
		(at 337.31708 -45.141134 -90)
		(property "Reference" "C1242"
			(at 0 0 90)
			(layer "B.SilkS")
			(hide yes)
			(effects
				(font
					(size 1.27 1.27)
				)
				(justify mirror)
			)
		)
		(property "Value" ""
			(at 0 0 90)
			(layer "B.Fab")
			(effects
				(font
					(size 1.27 1.27)
				)
				(justify mirror)
			)
		)
		(duplicate_pad_numbers_are_jumpers no)
		(fp_line
			(start -0.7874 0.4064)
			(end 0.7874 0.4064)
			(stroke
				(width 0.1524)
				(type default)
			)
			(layer "B.SilkS")
		)
		(fp_line
			(start 0.7874 0.4064)
			(end 0.7874 -0.4064)
			(stroke
				(width 0.1524)
				(type default)
			)
			(layer "B.SilkS")
		)
		(fp_line
			(start -0.7874 -0.4064)
			(end -0.7874 0.4064)
			(stroke
				(width 0.1524)
				(type default)
			)
			(layer "B.SilkS")
		)
		(fp_line
			(start 0.7874 -0.4064)
			(end -0.7874 -0.4064)
			(stroke
				(width 0.1524)
				(type default)
			)
			(layer "B.SilkS")
		)
		(fp_line
			(start -0.67945 0.3048)
			(end -0.120396 0.3048)
			(stroke
				(width 0.1)
				(type default)
			)
			(layer "B.Fab")
		)
		(fp_line
			(start -0.120396 0.3048)
			(end -0.120396 0.2794)
			(stroke
				(width 0.1)
				(type default)
			)
			(layer "B.Fab")
		)
		(fp_line
			(start 0.12065 0.3048)
			(end 0.67945 0.3048)
			(stroke
				(width 0.1)
				(type default)
			)
			(layer "B.Fab")
		)
		(fp_line
			(start 0.67945 0.3048)
			(end 0.67945 -0.305054)
			(stroke
				(width 0.1)
				(type default)
			)
			(layer "B.Fab")
		)
		(fp_line
			(start -0.120396 0.2794)
			(end 0.12065 0.2794)
			(stroke
				(width 0.1)
				(type default)
			)
			(layer "B.Fab")
		)
		(fp_line
			(start 0.12065 0.2794)
			(end 0.12065 0.3048)
			(stroke
				(width 0.1)
				(type default)
			)
			(layer "B.Fab")
		)
		(fp_line
			(start -0.12065 -0.2794)
			(end -0.12065 -0.3048)
			(stroke
				(width 0.1)
				(type default)
			)
			(layer "B.Fab")
		)
		(fp_line
			(start 0.12065 -0.2794)
			(end -0.12065 -0.2794)
			(stroke
				(width 0.1)
				(type default)
			)
			(layer "B.Fab")
		)
		(fp_line
			(start -0.67945 -0.3048)
			(end -0.67945 0.3048)
			(stroke
				(width 0.1)
				(type default)
			)
			(layer "B.Fab")
		)
		(fp_line
			(start -0.12065 -0.3048)
			(end -0.67945 -0.3048)
			(stroke
				(width 0.1)
				(type default)
			)
			(layer "B.Fab")
		)
		(fp_line
			(start 0.12065 -0.305054)
			(end 0.12065 -0.2794)
			(stroke
				(width 0.1)
				(type default)
			)
			(layer "B.Fab")
		)
		(fp_line
			(start 0.67945 -0.305054)
			(end 0.12065 -0.305054)
			(stroke
				(width 0.1)
				(type default)
			)
			(layer "B.Fab")
		)
		(pad "1" smd circle
			(at 0.40005 0 90)
			(size 0 0)
			(layers "B.Cu" "B.Mask" "B.Paste")
			(net "P1V05_PCH_AUX")
		)
		(pad "2" smd circle
			(at -0.40005 0 90)
			(size 0 0)
			(layers "B.Cu" "B.Mask" "B.Paste")
			(net "GND")
		)
	)
)
